# S9S_MB_2U (Grand Teton) — schematic netlist excerpt (pin names and nets, part order shuffled) for the footprints in the layout excerpt that follows; sources: Cadence DE-HDL packaged netlist, KiCad conversion of 03242023_DA0F0TMBIJ0_F0T_Motherboard_J_brd_V01_OCP.brd

C1001  Q_CAP  10UF 6.3V 20% X6S  pkg C0402  page 74 : A = PVCCIN_CPU0 ; B = GND
R1551  Q_RES  4.7K 1% EMPTY  pkg 0402LF  page 213 : A = P3V3_AUX ; B = SMB_1_PLD_3V3AUX_SDA_R1

(kicad_pcb
	(version 20260206)
	(generator "pcbnew")
	(generator_version "10.0")
	(general
		(thickness 1.6)
		(legacy_teardrops no)
	)
	(paper "A4")
	(title_block
		(title "03242023_DA0F0TMBIJ0_F0T_Motherboard_J_brd_V01_OCP.brd")
		(comment 1 "Grand Teton / footprints 390-391 of 6105")
	)
	(layers
		(0 "F.Cu" signal "TOP")
		(4 "In1.Cu" signal "GND")
		(6 "In2.Cu" signal "IN1")
		(8 "In3.Cu" signal "GND1")
		(10 "In4.Cu" signal "IN2")
		(12 "In5.Cu" signal "GND2")
		(14 "In6.Cu" signal "IN3")
		(16 "In7.Cu" signal "GND3")
		(18 "In8.Cu" signal "VCC")
		(20 "In9.Cu" signal "VCC1")
		(22 "In10.Cu" signal "GND4")
		(24 "In11.Cu" signal "IN4")
		(26 "In12.Cu" signal "GND5")
		(28 "In13.Cu" signal "IN5")
		(30 "In14.Cu" signal "GND6")
		(32 "In15.Cu" signal "IN6")
		(34 "In16.Cu" signal "GND7")
		(2 "B.Cu" signal "BOTTOM")
		(9 "F.Adhes" user "F.Adhesive")
		(11 "B.Adhes" user "B.Adhesive")
		(13 "F.Paste" user "Package Geometry/Pastemask Top")
		(15 "B.Paste" user "Package Geometry/Pastemask Bottom")
		(5 "F.SilkS" user "Ref Des/Silkscreen Top")
		(7 "B.SilkS" user "Ref Des/Silkscreen Bottom")
		(1 "F.Mask" user "Board Geometry/Soldermask Top")
		(3 "B.Mask" user "Board Geometry/Soldermask Bottom")
		(17 "Dwgs.User" user "User.Drawings")
		(19 "Cmts.User" user "User.Comments")
		(21 "Eco1.User" user "User.Eco1")
		(23 "Eco2.User" user "User.Eco2")
		(25 "Edge.Cuts" user "Board Geometry/Outline")
		(27 "Margin" user)
		(31 "F.CrtYd" user "Package Geometry/Place Bound Top")
		(29 "B.CrtYd" user "Package Geometry/Place Bound Bottom")
		(35 "F.Fab" user "Ref Des/Assembly Top")
		(33 "B.Fab" user "Ref Des/Assembly Bottom")
	)
	(footprint ""
		(layer "F.Cu")
		(at 365.46663 -245.634002 -90)
		(property "Reference" "C1001"
			(at 0 0 270)
			(layer "F.SilkS")
			(hide yes)
			(effects
				(font
					(size 1.27 1.27)
				)
			)
		)
		(property "Value" ""
			(at 0 0 270)
			(layer "F.Fab")
			(effects
				(font
					(size 1.27 1.27)
				)
			)
		)
		(duplicate_pad_numbers_are_jumpers no)
		(fp_line
			(start -0.7874 0.4064)
			(end -0.7874 -0.4064)
			(stroke
				(width 0.1524)
				(type default)
			)
			(layer "F.SilkS")
		)
		(fp_line
			(start 0.7874 0.4064)
			(end -0.7874 0.4064)
			(stroke
				(width 0.1524)
				(type default)
			)
			(layer "F.SilkS")
		)
		(fp_line
			(start -0.7874 -0.4064)
			(end 0.7874 -0.4064)
			(stroke
				(width 0.1524)
				(type default)
			)
			(layer "F.SilkS")
		)
		(fp_line
			(start 0.7874 -0.4064)
			(end 0.7874 0.4064)
			(stroke
				(width 0.1524)
				(type default)
			)
			(layer "F.SilkS")
		)
		(fp_line
			(start -0.67945 0.3048)
			(end -0.67945 -0.305054)
			(stroke
				(width 0.1)
				(type default)
			)
			(layer "F.Fab")
		)
		(fp_line
			(start -0.12065 0.3048)
			(end -0.67945 0.3048)
			(stroke
				(width 0.1)
				(type default)
			)
			(layer "F.Fab")
		)
		(fp_line
			(start 0.120396 0.3048)
			(end 0.120396 0.2794)
			(stroke
				(width 0.1)
				(type default)
			)
			(layer "F.Fab")
		)
		(fp_line
			(start 0.67945 0.3048)
			(end 0.120396 0.3048)
			(stroke
				(width 0.1)
				(type default)
			)
			(layer "F.Fab")
		)
		(fp_line
			(start -0.12065 0.2794)
			(end -0.12065 0.3048)
			(stroke
				(width 0.1)
				(type default)
			)
			(layer "F.Fab")
		)
		(fp_line
			(start 0.120396 0.2794)
			(end -0.12065 0.2794)
			(stroke
				(width 0.1)
				(type default)
			)
			(layer "F.Fab")
		)
		(fp_line
			(start -0.12065 -0.2794)
			(end 0.12065 -0.2794)
			(stroke
				(width 0.1)
				(type default)
			)
			(layer "F.Fab")
		)
		(fp_line
			(start 0.12065 -0.2794)
			(end 0.12065 -0.3048)
			(stroke
				(width 0.1)
				(type default)
			)
			(layer "F.Fab")
		)
		(fp_line
			(start 0.12065 -0.3048)
			(end 0.67945 -0.3048)
			(stroke
				(width 0.1)
				(type default)
			)
			(layer "F.Fab")
		)
		(fp_line
			(start 0.67945 -0.3048)
			(end 0.67945 0.3048)
			(stroke
				(width 0.1)
				(type default)
			)
			(layer "F.Fab")
		)
		(fp_line
			(start -0.67945 -0.305054)
			(end -0.12065 -0.305054)
			(stroke
				(width 0.1)
				(type default)
			)
			(layer "F.Fab")
		)
		(fp_line
			(start -0.12065 -0.305054)
			(end -0.12065 -0.2794)
			(stroke
				(width 0.1)
				(type default)
			)
			(layer "F.Fab")
		)
		(pad "1" smd circle
			(at -0.40005 0 270)
			(size 0 0)
			(layers "F.Cu" "F.Mask" "F.Paste")
			(net "PVCCIN_CPU0")
		)
		(pad "2" smd circle
			(at 0.40005 0 270)
			(size 0 0)
			(layers "F.Cu" "F.Mask" "F.Paste")
			(net "GND")
		)
	)
	(footprint ""
		(layer "F.Cu")
		(at 164.64788 -116.296948)
		(property "Reference" "R1551"
			(at 0 0 0)
			(layer "F.SilkS")
			(hide yes)
			(effects
				(font
					(size 1.27 1.27)
				)
			)
		)
		(property "Value" ""
			(at 0 0 0)
			(layer "F.Fab")
			(effects
				(font
					(size 1.27 1.27)
				)
			)
		)
		(duplicate_pad_numbers_are_jumpers no)
		(fp_line
			(start -0.7874 -0.4064)
			(end 0.7874 -0.4064)
			(stroke
				(width 0.1524)
				(type default)
			)
			(layer "F.SilkS")
		)
		(fp_line
			(start -0.7874 0.4064)
			(end -0.7874 -0.4064)
			(stroke
				(width 0.1524)
				(type default)
			)
			(layer "F.SilkS")
		)
		(fp_line
			(start 0.7874 -0.4064)
			(end 0.7874 0.4064)
			(stroke
				(width 0.1524)
				(type default)
			)
			(layer "F.SilkS")
		)
		(fp_line
			(start 0.7874 0.4064)
			(end -0.7874 0.4064)
			(stroke
				(width 0.1524)
				(type default)
			)
			(layer "F.SilkS")
		)
		(fp_line
			(start -0.67945 -0.305054)
			(end -0.12065 -0.305054)
			(stroke
				(width 0.1)
				(type default)
			)
			(layer "F.Fab")
		)
		(fp_line
			(start -0.67945 0.3048)
			(end -0.67945 -0.305054)
			(stroke
				(width 0.1)
				(type default)
			)
			(layer "F.Fab")
		)
		(fp_line
			(start -0.12065 -0.305054)
			(end -0.12065 -0.2794)
			(stroke
				(width 0.1)
				(type default)
			)
			(layer "F.Fab")
		)
		(fp_line
			(start -0.12065 -0.2794)
			(end 0.12065 -0.2794)
			(stroke
				(width 0.1)
				(type default)
			)
			(layer "F.Fab")
		)
		(fp_line
			(start -0.12065 0.2794)
			(end -0.12065 0.3048)
			(stroke
				(width 0.1)
				(type default)
			)
			(layer "F.Fab")
		)
		(fp_line
			(start -0.12065 0.3048)
			(end -0.67945 0.3048)
			(stroke
				(width 0.1)
				(type default)
			)
			(layer "F.Fab")
		)
		(fp_line
			(start 0.120396 0.2794)
			(end -0.12065 0.2794)
			(stroke
				(width 0.1)
				(type default)
			)
			(layer "F.Fab")
		)
		(fp_line
			(start 0.120396 0.3048)
			(end 0.120396 0.2794)
			(stroke
				(width 0.1)
				(type default)
			)
			(layer "F.Fab")
		)
		(fp_line
			(start 0.12065 -0.3048)
			(end 0.67945 -0.3048)
			(stroke
				(width 0.1)
				(type default)
			)
			(layer "F.Fab")
		)
		(fp_line
			(start 0.12065 -0.2794)
			(end 0.12065 -0.3048)
			(stroke
				(width 0.1)
				(type default)
			)
			(layer "F.Fab")
		)
		(fp_line
			(start 0.67945 -0.3048)
			(end 0.67945 0.3048)
			(stroke
				(width 0.1)
				(type default)
			)
			(layer "F.Fab")
		)
		(fp_line
			(start 0.67945 0.3048)
			(end 0.120396 0.3048)
			(stroke
				(width 0.1)
				(type default)
			)
			(layer "F.Fab")
		)
		(pad "1" smd circle
			(at -0.40005 0)
			(size 0 0)
			(layers "F.Cu" "F.Mask" "F.Paste")
			(net "P3V3_AUX")
		)
		(pad "2" smd circle
			(at 0.40005 0)
			(size 0 0)
			(layers "F.Cu" "F.Mask" "F.Paste")
			(net "SMB_1_PLD_3V3AUX_SDA_R1")
		)
	)
)
